# S9S_MB_2U (Grand Teton) — schematic netlist excerpt (pin names and nets, part order shuffled) for the footprints in the layout excerpt that follows; sources: Cadence DE-HDL packaged netlist, KiCad conversion of 03242023_DA0F0TMBIJ0_F0T_Motherboard_J_brd_V01_OCP.brd

R4643  Q_RES  1K 1% EMPTY  pkg 0402LF  page 167 : A = P3V3_AUX ; B = FM_P2E_BUF2_VODA_DB
PC397_P1_1  Q_CAP  3300PF 50V 10% X7R  pkg 0402  page 289 : A = SW_P12V_PVCCFA_EHV_FIVRA_CPU1_R ; B = GND

(kicad_pcb
	(version 20260206)
	(generator "pcbnew")
	(generator_version "10.0")
	(general
		(thickness 1.6)
		(legacy_teardrops no)
	)
	(paper "A4")
	(title_block
		(title "03242023_DA0F0TMBIJ0_F0T_Motherboard_J_brd_V01_OCP.brd")
		(comment 1 "Grand Teton / footprints 2500-2501 of 6105")
	)
	(layers
		(0 "F.Cu" signal "TOP")
		(4 "In1.Cu" signal "GND")
		(6 "In2.Cu" signal "IN1")
		(8 "In3.Cu" signal "GND1")
		(10 "In4.Cu" signal "IN2")
		(12 "In5.Cu" signal "GND2")
		(14 "In6.Cu" signal "IN3")
		(16 "In7.Cu" signal "GND3")
		(18 "In8.Cu" signal "VCC")
		(20 "In9.Cu" signal "VCC1")
		(22 "In10.Cu" signal "GND4")
		(24 "In11.Cu" signal "IN4")
		(26 "In12.Cu" signal "GND5")
		(28 "In13.Cu" signal "IN5")
		(30 "In14.Cu" signal "GND6")
		(32 "In15.Cu" signal "IN6")
		(34 "In16.Cu" signal "GND7")
		(2 "B.Cu" signal "BOTTOM")
		(9 "F.Adhes" user "F.Adhesive")
		(11 "B.Adhes" user "B.Adhesive")
		(13 "F.Paste" user "Package Geometry/Pastemask Top")
		(15 "B.Paste" user "Package Geometry/Pastemask Bottom")
		(5 "F.SilkS" user "Ref Des/Silkscreen Top")
		(7 "B.SilkS" user "Ref Des/Silkscreen Bottom")
		(1 "F.Mask" user "Board Geometry/Soldermask Top")
		(3 "B.Mask" user "Board Geometry/Soldermask Bottom")
		(17 "Dwgs.User" user "User.Drawings")
		(19 "Cmts.User" user "User.Comments")
		(21 "Eco1.User" user "User.Eco1")
		(23 "Eco2.User" user "User.Eco2")
		(25 "Edge.Cuts" user "Board Geometry/Outline")
		(27 "Margin" user)
		(31 "F.CrtYd" user "Package Geometry/Place Bound Top")
		(29 "B.CrtYd" user "Package Geometry/Place Bound Bottom")
		(35 "F.Fab" user "Ref Des/Assembly Top")
		(33 "B.Fab" user "Ref Des/Assembly Bottom")
	)
	(footprint ""
		(layer "F.Cu")
		(at 49.347882 -393.30122 180)
		(property "Reference" "R4643"
			(at 0 0 180)
			(layer "F.SilkS")
			(hide yes)
			(effects
				(font
					(size 1.27 1.27)
				)
			)
		)
		(property "Value" ""
			(at 0 0 180)
			(layer "F.Fab")
			(effects
				(font
					(size 1.27 1.27)
				)
			)
		)
		(duplicate_pad_numbers_are_jumpers no)
		(fp_line
			(start 0.7874 0.4064)
			(end -0.7874 0.4064)
			(stroke
				(width 0.1524)
				(type default)
			)
			(layer "F.SilkS")
		)
		(fp_line
			(start 0.7874 -0.4064)
			(end 0.7874 0.4064)
			(stroke
				(width 0.1524)
				(type default)
			)
			(layer "F.SilkS")
		)
		(fp_line
			(start -0.7874 0.4064)
			(end -0.7874 -0.4064)
			(stroke
				(width 0.1524)
				(type default)
			)
			(layer "F.SilkS")
		)
		(fp_line
			(start -0.7874 -0.4064)
			(end 0.7874 -0.4064)
			(stroke
				(width 0.1524)
				(type default)
			)
			(layer "F.SilkS")
		)
		(fp_line
			(start 0.67945 0.3048)
			(end 0.120396 0.3048)
			(stroke
				(width 0.1)
				(type default)
			)
			(layer "F.Fab")
		)
		(fp_line
			(start 0.67945 -0.3048)
			(end 0.67945 0.3048)
			(stroke
				(width 0.1)
				(type default)
			)
			(layer "F.Fab")
		)
		(fp_line
			(start 0.12065 -0.2794)
			(end 0.12065 -0.3048)
			(stroke
				(width 0.1)
				(type default)
			)
			(layer "F.Fab")
		)
		(fp_line
			(start 0.12065 -0.3048)
			(end 0.67945 -0.3048)
			(stroke
				(width 0.1)
				(type default)
			)
			(layer "F.Fab")
		)
		(fp_line
			(start 0.120396 0.3048)
			(end 0.120396 0.2794)
			(stroke
				(width 0.1)
				(type default)
			)
			(layer "F.Fab")
		)
		(fp_line
			(start 0.120396 0.2794)
			(end -0.12065 0.2794)
			(stroke
				(width 0.1)
				(type default)
			)
			(layer "F.Fab")
		)
		(fp_line
			(start -0.12065 0.3048)
			(end -0.67945 0.3048)
			(stroke
				(width 0.1)
				(type default)
			)
			(layer "F.Fab")
		)
		(fp_line
			(start -0.12065 0.2794)
			(end -0.12065 0.3048)
			(stroke
				(width 0.1)
				(type default)
			)
			(layer "F.Fab")
		)
		(fp_line
			(start -0.12065 -0.2794)
			(end 0.12065 -0.2794)
			(stroke
				(width 0.1)
				(type default)
			)
			(layer "F.Fab")
		)
		(fp_line
			(start -0.12065 -0.305054)
			(end -0.12065 -0.2794)
			(stroke
				(width 0.1)
				(type default)
			)
			(layer "F.Fab")
		)
		(fp_line
			(start -0.67945 0.3048)
			(end -0.67945 -0.305054)
			(stroke
				(width 0.1)
				(type default)
			)
			(layer "F.Fab")
		)
		(fp_line
			(start -0.67945 -0.305054)
			(end -0.12065 -0.305054)
			(stroke
				(width 0.1)
				(type default)
			)
			(layer "F.Fab")
		)
		(pad "1" smd circle
			(at -0.40005 0 180)
			(size 0 0)
			(layers "F.Cu" "F.Mask" "F.Paste")
			(net "P3V3_AUX")
		)
		(pad "2" smd circle
			(at 0.40005 0 180)
			(size 0 0)
			(layers "F.Cu" "F.Mask" "F.Paste")
			(net "FM_P2E_BUF2_VODA_DB")
		)
	)
	(footprint ""
		(layer "F.Cu")
		(at 176.63795 -353.62261 -90)
		(property "Reference" "PC397_P1_1"
			(at 0 0 270)
			(layer "F.SilkS")
			(hide yes)
			(effects
				(font
					(size 1.27 1.27)
				)
			)
		)
		(property "Value" ""
			(at 0 0 270)
			(layer "F.Fab")
			(effects
				(font
					(size 1.27 1.27)
				)
			)
		)
		(duplicate_pad_numbers_are_jumpers no)
		(fp_line
			(start -0.7874 0.4064)
			(end -0.7874 -0.4064)
			(stroke
				(width 0.1524)
				(type default)
			)
			(layer "F.SilkS")
		)
		(fp_line
			(start 0.7874 0.4064)
			(end -0.7874 0.4064)
			(stroke
				(width 0.1524)
				(type default)
			)
			(layer "F.SilkS")
		)
		(fp_line
			(start -0.7874 -0.4064)
			(end 0.7874 -0.4064)
			(stroke
				(width 0.1524)
				(type default)
			)
			(layer "F.SilkS")
		)
		(fp_line
			(start 0.7874 -0.4064)
			(end 0.7874 0.4064)
			(stroke
				(width 0.1524)
				(type default)
			)
			(layer "F.SilkS")
		)
		(fp_line
			(start -0.67945 0.3048)
			(end -0.67945 -0.305054)
			(stroke
				(width 0.1)
				(type default)
			)
			(layer "F.Fab")
		)
		(fp_line
			(start -0.12065 0.3048)
			(end -0.67945 0.3048)
			(stroke
				(width 0.1)
				(type default)
			)
			(layer "F.Fab")
		)
		(fp_line
			(start 0.120396 0.3048)
			(end 0.120396 0.2794)
			(stroke
				(width 0.1)
				(type default)
			)
			(layer "F.Fab")
		)
		(fp_line
			(start 0.67945 0.3048)
			(end 0.120396 0.3048)
			(stroke
				(width 0.1)
				(type default)
			)
			(layer "F.Fab")
		)
		(fp_line
			(start -0.12065 0.2794)
			(end -0.12065 0.3048)
			(stroke
				(width 0.1)
				(type default)
			)
			(layer "F.Fab")
		)
		(fp_line
			(start 0.120396 0.2794)
			(end -0.12065 0.2794)
			(stroke
				(width 0.1)
				(type default)
			)
			(layer "F.Fab")
		)
		(fp_line
			(start -0.12065 -0.2794)
			(end 0.12065 -0.2794)
			(stroke
				(width 0.1)
				(type default)
			)
			(layer "F.Fab")
		)
		(fp_line
			(start 0.12065 -0.2794)
			(end 0.12065 -0.3048)
			(stroke
				(width 0.1)
				(type default)
			)
			(layer "F.Fab")
		)
		(fp_line
			(start 0.12065 -0.3048)
			(end 0.67945 -0.3048)
			(stroke
				(width 0.1)
				(type default)
			)
			(layer "F.Fab")
		)
		(fp_line
			(start 0.67945 -0.3048)
			(end 0.67945 0.3048)
			(stroke
				(width 0.1)
				(type default)
			)
			(layer "F.Fab")
		)
		(fp_line
			(start -0.67945 -0.305054)
			(end -0.12065 -0.305054)
			(stroke
				(width 0.1)
				(type default)
			)
			(layer "F.Fab")
		)
		(fp_line
			(start -0.12065 -0.305054)
			(end -0.12065 -0.2794)
			(stroke
				(width 0.1)
				(type default)
			)
			(layer "F.Fab")
		)
		(pad "1" smd circle
			(at -0.40005 0 270)
			(size 0 0)
			(layers "F.Cu" "F.Mask" "F.Paste")
			(net "SW_P12V_PVCCFA_EHV_FIVRA_CPU1_R")
		)
		(pad "2" smd circle
			(at 0.40005 0 270)
			(size 0 0)
			(layers "F.Cu" "F.Mask" "F.Paste")
			(net "GND")
		)
	)
)
